(kicad_pcb
	(version 20260206)
	(generator "pcbnew")
	(generator_version "10.0")
	(general
		(thickness 1.6)
		(legacy_teardrops no)
	)
	(paper "A4")
	(title_block
		(title "dpb — 14545-sa.0730WZS0815.brd")
		(comment 1 "Honey Badger (Wiwynn) / footprints 880-887 of 1066")
	)
	(layers
		(0 "F.Cu" signal "TOP")
		(4 "In1.Cu" signal "L2GND")
		(6 "In2.Cu" signal "L3")
		(8 "In3.Cu" signal "L4VCC")
		(10 "In4.Cu" signal "L5VCC")
		(12 "In5.Cu" signal "L6")
		(14 "In6.Cu" signal "L7GND")
		(2 "B.Cu" signal "BOTTOM")
		(9 "F.Adhes" user "F.Adhesive")
		(11 "B.Adhes" user "B.Adhesive")
		(13 "F.Paste" user "Package Geometry/Pastemask Top")
		(15 "B.Paste" user "Package Geometry/Pastemask Bottom")
		(5 "F.SilkS" user "Ref Des/Silkscreen Top")
		(7 "B.SilkS" user "Ref Des/Silkscreen Bottom")
		(1 "F.Mask" user "Board Geometry/Soldermask Top")
		(3 "B.Mask" user "Board Geometry/Soldermask Bottom")
		(17 "Dwgs.User" user "User.Drawings")
		(19 "Cmts.User" user "User.Comments")
		(21 "Eco1.User" user "User.Eco1")
		(23 "Eco2.User" user "User.Eco2")
		(25 "Edge.Cuts" user "Board Geometry/Outline")
		(27 "Margin" user)
		(31 "F.CrtYd" user "Package Geometry/Place Bound Top")
		(29 "B.CrtYd" user "Package Geometry/Place Bound Bottom")
		(35 "F.Fab" user "Ref Des/Assembly Top")
		(33 "B.Fab" user "Ref Des/Assembly Bottom")
	)
	(footprint ""
		(layer "F.Cu")
		(at 30.608778 -336.091784)
		(property "Reference" "R465"
			(at 0 0 0)
			(layer "F.SilkS")
			(hide yes)
			(effects
				(font
					(size 1.27 1.27)
				)
			)
		)
		(property "Value" "4K7R2J-2-GP"
			(at 0.064008 -3.993896 0)
			(unlocked yes)
			(layer "F.Fab")
			(hide yes)
			(effects
				(font
					(size 1.016 1.016)
					(thickness 0.1524)
				)
			)
		)
		(property "Device Type" "R402H16"
			(at 0.064008 -5.517896 0)
			(unlocked yes)
			(layer "F.Fab")
			(hide yes)
			(effects
				(font
					(size 1.016 1.016)
					(thickness 0.1524)
				)
			)
		)
		(duplicate_pad_numbers_are_jumpers no)
		(fp_line
			(start -0.508 -0.9398)
			(end -0.508 0.9398)
			(stroke
				(width 0.1524)
				(type default)
			)
			(layer "F.SilkS")
		)
		(fp_line
			(start 0.508 -0.9398)
			(end -0.508 -0.9398)
			(stroke
				(width 0.1524)
				(type default)
			)
			(layer "F.SilkS")
		)
		(fp_rect
			(start -0.508 0.9398)
			(end 0.508 -0.9398)
			(stroke
				(width 0)
				(type default)
			)
			(fill no)
			(layer "F.CrtYd")
		)
		(fp_rect
			(start -0.508 0.9398)
			(end 0.508 -0.9398)
			(stroke
				(width 0)
				(type default)
			)
			(fill no)
			(layer "F.Fab")
		)
		(pad "1" smd custom
			(at 0 -0.4445)
			(size 0.1397 0.1397)
			(layers "F.Cu" "F.Mask" "F.Paste")
			(net "P3V3")
			(options
				(clearance outline)
				(anchor circle)
			)
			(primitives
				(gr_poly
					(pts
						(arc
							(start -0.1778 -0.2794)
							(mid -0.249642 -0.249642)
							(end -0.2794 -0.1778)
						)
						(arc
							(start -0.2794 0.1778)
							(mid -0.249642 0.249642)
							(end -0.1778 0.2794)
						)
						(arc
							(start 0.1778 0.2794)
							(mid 0.249642 0.249642)
							(end 0.2794 0.1778)
						)
						(arc
							(start 0.2794 -0.1778)
							(mid 0.249642 -0.249642)
							(end 0.1778 -0.2794)
						)
					)
					(width 0)
					(fill yes)
				)
			)
		)
		(pad "2" smd custom
			(at 0 0.4445)
			(size 0.1397 0.1397)
			(layers "F.Cu" "F.Mask" "F.Paste")
			(net "SAS2X28_B_HDD11_FLT")
			(options
				(clearance outline)
				(anchor circle)
			)
			(primitives
				(gr_poly
					(pts
						(arc
							(start -0.1778 -0.2794)
							(mid -0.249642 -0.249642)
							(end -0.2794 -0.1778)
						)
						(arc
							(start -0.2794 0.1778)
							(mid -0.249642 0.249642)
							(end -0.1778 0.2794)
						)
						(arc
							(start 0.1778 0.2794)
							(mid 0.249642 0.249642)
							(end 0.2794 0.1778)
						)
						(arc
							(start 0.2794 -0.1778)
							(mid 0.249642 -0.249642)
							(end 0.1778 -0.2794)
						)
					)
					(width 0)
					(fill yes)
				)
			)
		)
	)
	(footprint ""
		(layer "F.Cu")
		(at 210.819746 -42.4307 -90)
		(property "Reference" "R341"
			(at 0 0 270)
			(layer "F.SilkS")
			(hide yes)
			(effects
				(font
					(size 1.27 1.27)
				)
			)
		)
		(property "Value" "4K7R2J-2-GP"
			(at 0.064008 -3.993896 270)
			(unlocked yes)
			(layer "F.Fab")
			(hide yes)
			(effects
				(font
					(size 1.016 1.016)
					(thickness 0.1524)
				)
			)
		)
		(property "Device Type" "R402H16"
			(at 0.064008 -5.517896 270)
			(unlocked yes)
			(layer "F.Fab")
			(hide yes)
			(effects
				(font
					(size 1.016 1.016)
					(thickness 0.1524)
				)
			)
		)
		(duplicate_pad_numbers_are_jumpers no)
		(fp_line
			(start -0.508 -0.9398)
			(end -0.508 0.9398)
			(stroke
				(width 0.1524)
				(type default)
			)
			(layer "F.SilkS")
		)
		(fp_line
			(start 0.508 -0.9398)
			(end -0.508 -0.9398)
			(stroke
				(width 0.1524)
				(type default)
			)
			(layer "F.SilkS")
		)
		(fp_rect
			(start -0.508 0.9398)
			(end 0.508 -0.9398)
			(stroke
				(width 0)
				(type default)
			)
			(fill no)
			(layer "F.CrtYd")
		)
		(fp_rect
			(start -0.508 0.9398)
			(end 0.508 -0.9398)
			(stroke
				(width 0)
				(type default)
			)
			(fill no)
			(layer "F.Fab")
		)
		(pad "1" smd custom
			(at 0 -0.4445 270)
			(size 0.1397 0.1397)
			(layers "F.Cu" "F.Mask" "F.Paste")
			(net "I2C_B_TMP4_A0")
			(options
				(clearance outline)
				(anchor circle)
			)
			(primitives
				(gr_poly
					(pts
						(arc
							(start -0.1778 -0.2794)
							(mid -0.249642 -0.249642)
							(end -0.2794 -0.1778)
						)
						(arc
							(start -0.2794 0.1778)
							(mid -0.249642 0.249642)
							(end -0.1778 0.2794)
						)
						(arc
							(start 0.1778 0.2794)
							(mid 0.249642 0.249642)
							(end 0.2794 0.1778)
						)
						(arc
							(start 0.2794 -0.1778)
							(mid 0.249642 -0.249642)
							(end 0.1778 -0.2794)
						)
					)
					(width 0)
					(fill yes)
				)
			)
		)
		(pad "2" smd custom
			(at 0 0.4445 270)
			(size 0.1397 0.1397)
			(layers "F.Cu" "F.Mask" "F.Paste")
			(net "GND")
			(options
				(clearance outline)
				(anchor circle)
			)
			(primitives
				(gr_poly
					(pts
						(arc
							(start -0.1778 -0.2794)
							(mid -0.249642 -0.249642)
							(end -0.2794 -0.1778)
						)
						(arc
							(start -0.2794 0.1778)
							(mid -0.249642 0.249642)
							(end -0.1778 0.2794)
						)
						(arc
							(start 0.1778 0.2794)
							(mid 0.249642 0.249642)
							(end 0.2794 0.1778)
						)
						(arc
							(start 0.2794 -0.1778)
							(mid 0.249642 -0.249642)
							(end 0.1778 -0.2794)
						)
					)
					(width 0)
					(fill yes)
				)
			)
		)
	)
	(footprint ""
		(layer "F.Cu")
		(at 27.2923 -342.4174 -90)
		(property "Reference" "C39"
			(at 0 0 270)
			(layer "F.SilkS")
			(hide yes)
			(effects
				(font
					(size 1.27 1.27)
				)
			)
		)
		(property "Value" "SCD01U50V2KX-1GP"
			(at 1.1811 -2.7051 270)
			(unlocked yes)
			(layer "F.Fab")
			(hide yes)
			(effects
				(font
					(size 1.016 1.016)
					(thickness 0.1524)
				)
			)
		)
		(property "Device Type" "C402H22"
			(at 1.1811 -4.2291 270)
			(unlocked yes)
			(layer "F.Fab")
			(hide yes)
			(effects
				(font
					(size 1.016 1.016)
					(thickness 0.1524)
				)
			)
		)
		(duplicate_pad_numbers_are_jumpers no)
		(fp_rect
			(start -0.4318 0.9525)
			(end 0.4318 -0.9525)
			(stroke
				(width 0)
				(type default)
			)
			(fill no)
			(layer "F.CrtYd")
		)
		(fp_rect
			(start -0.4318 0.9525)
			(end 0.4318 -0.9525)
			(stroke
				(width 0)
				(type default)
			)
			(fill no)
			(layer "F.Fab")
		)
		(pad "1" smd custom
			(at 0 -0.4445 270)
			(size 0.1524 0.1524)
			(layers "F.Cu" "F.Mask" "F.Paste")
			(net "SEB_AB_TX-")
			(options
				(clearance outline)
				(anchor circle)
			)
			(primitives
				(gr_poly
					(pts
						(arc
							(start 0.3048 -0.2032)
							(mid 0.275042 -0.275042)
							(end 0.2032 -0.3048)
						)
						(arc
							(start -0.2032 -0.3048)
							(mid -0.275042 -0.275042)
							(end -0.3048 -0.2032)
						)
						(arc
							(start -0.3048 0.2032)
							(mid -0.275042 0.275042)
							(end -0.2032 0.3048)
						)
						(arc
							(start 0.2032 0.3048)
							(mid 0.275042 0.275042)
							(end 0.3048 0.2032)
						)
					)
					(width 0)
					(fill yes)
				)
			)
		)
		(pad "2" smd custom
			(at 0 0.4445 270)
			(size 0.1524 0.1524)
			(layers "F.Cu" "F.Mask" "F.Paste")
			(net "SEB_AB_RX-")
			(options
				(clearance outline)
				(anchor circle)
			)
			(primitives
				(gr_poly
					(pts
						(arc
							(start 0.3048 -0.2032)
							(mid 0.275042 -0.275042)
							(end 0.2032 -0.3048)
						)
						(arc
							(start -0.2032 -0.3048)
							(mid -0.275042 -0.275042)
							(end -0.3048 -0.2032)
						)
						(arc
							(start -0.3048 0.2032)
							(mid -0.275042 0.275042)
							(end -0.2032 0.3048)
						)
						(arc
							(start 0.2032 0.3048)
							(mid 0.275042 0.275042)
							(end 0.3048 0.2032)
						)
					)
					(width 0)
					(fill yes)
				)
			)
		)
	)
	(footprint ""
		(layer "F.Cu")
		(at 211.454746 -491.6297)
		(property "Reference" "C112"
			(at 0 0 0)
			(layer "F.SilkS")
			(hide yes)
			(effects
				(font
					(size 1.27 1.27)
				)
			)
		)
		(property "Value" "SC10U25V6KX-1GP"
			(at -0.0762 -5.1308 0)
			(unlocked yes)
			(layer "F.Fab")
			(hide yes)
			(effects
				(font
					(size 1.016 1.016)
					(thickness 0.1524)
				)
			)
		)
		(property "Device Type" "C1206H71"
			(at -0.127 -6.6548 0)
			(unlocked yes)
			(layer "F.Fab")
			(hide yes)
			(effects
				(font
					(size 1.016 1.016)
					(thickness 0.1524)
				)
			)
		)
		(duplicate_pad_numbers_are_jumpers no)
		(fp_line
			(start -1.016 -2.2352)
			(end 1.016 -2.2352)
			(stroke
				(width 0.1524)
				(type default)
			)
			(layer "F.SilkS")
		)
		(fp_line
			(start -1.016 -0.8382)
			(end -1.016 -2.2352)
			(stroke
				(width 0.1524)
				(type default)
			)
			(layer "F.SilkS")
		)
		(fp_line
			(start -1.016 2.2352)
			(end -1.016 0.8382)
			(stroke
				(width 0.1524)
				(type default)
			)
			(layer "F.SilkS")
		)
		(fp_line
			(start 1.016 -2.2352)
			(end 1.016 -0.8382)
			(stroke
				(width 0.1524)
				(type default)
			)
			(layer "F.SilkS")
		)
		(fp_line
			(start 1.016 0.8382)
			(end 1.016 2.2352)
			(stroke
				(width 0.1524)
				(type default)
			)
			(layer "F.SilkS")
		)
		(fp_line
			(start 1.016 2.2352)
			(end -1.016 2.2352)
			(stroke
				(width 0.1524)
				(type default)
			)
			(layer "F.SilkS")
		)
		(fp_rect
			(start -1.0922 2.3114)
			(end 1.0922 -2.3114)
			(stroke
				(width 0)
				(type default)
			)
			(fill no)
			(layer "F.CrtYd")
		)
		(fp_poly
			(pts
				(xy 1.0922 -2.3114) (xy 1.0922 2.3114) (xy -1.0922 2.3114) (xy -1.0922 -2.3114)
			)
			(stroke
				(width 0)
				(type default)
			)
			(fill no)
			(layer "F.Fab")
		)
		(pad "1" smd rect
			(at 0 -1.397)
			(size 1.651 1.27)
			(layers "F.Cu" "F.Mask" "F.Paste")
			(net "P12V_HDD0")
		)
		(pad "2" smd rect
			(at 0 1.397)
			(size 1.651 1.27)
			(layers "F.Cu" "F.Mask" "F.Paste")
			(net "GND")
		)
	)
	(footprint ""
		(layer "F.Cu")
		(at 73.405746 -183.7817)
		(property "Reference" "TP33"
			(at 0 0 0)
			(layer "F.SilkS")
			(hide yes)
			(effects
				(font
					(size 1.27 1.27)
				)
			)
		)
		(property "Value" "TPAD32-GP"
			(at 0 -3.166364 0)
			(unlocked yes)
			(layer "F.Fab")
			(hide yes)
			(effects
				(font
					(size 1.016 1.016)
					(thickness 0.1524)
				)
			)
		)
		(property "Device Type" "TPAD32"
			(at 0 -4.690618 0)
			(unlocked yes)
			(layer "F.Fab")
			(hide yes)
			(effects
				(font
					(size 1.016 1.016)
					(thickness 0.1524)
				)
			)
		)
		(duplicate_pad_numbers_are_jumpers no)
		(fp_poly
			(pts
				(arc
					(start 0.4064 0)
					(mid -0.4064 0)
					(end 0.4064 0)
				)
			)
			(stroke
				(width 0)
				(type default)
			)
			(fill no)
			(layer "F.CrtYd")
		)
		(fp_poly
			(pts
				(arc
					(start 0.7112 0)
					(mid -0.7112 0)
					(end 0.7112 0)
				)
			)
			(stroke
				(width 0)
				(type default)
			)
			(fill no)
			(layer "F.Fab")
		)
		(pad "1" smd circle
			(at 0 0)
			(size 0.8128 0.8128)
			(layers "F.Cu" "F.Mask" "F.Paste")
			(net "ACT_HDD8")
		)
	)
	(footprint ""
		(layer "F.Cu")
		(at 200.024746 -184.2897)
		(property "Reference" "U10"
			(at 0 0 0)
			(layer "F.SilkS")
			(hide yes)
			(effects
				(font
					(size 1.27 1.27)
				)
			)
		)
		(property "Value" "74LVC1G08GW-1-GP"
			(at -2.3368 -8.6868 0)
			(unlocked yes)
			(layer "F.Fab")
			(hide yes)
			(effects
				(font
					(size 1.016 1.016)
					(thickness 0.1524)
				)
			)
		)
		(property "Device Type" "SC70-5H44"
			(at -2.3114 -10.414 0)
			(unlocked yes)
			(layer "F.Fab")
			(hide yes)
			(effects
				(font
					(size 1.016 1.016)
					(thickness 0.1524)
				)
			)
		)
		(duplicate_pad_numbers_are_jumpers no)
		(fp_line
			(start -1.27 -1.7018)
			(end 1.27 -1.7018)
			(stroke
				(width 0.1524)
				(type default)
			)
			(layer "F.SilkS")
		)
		(fp_line
			(start -1.27 1.7018)
			(end -1.27 -1.7018)
			(stroke
				(width 0.1524)
				(type default)
			)
			(layer "F.SilkS")
		)
		(fp_line
			(start 0.6604 -1.8034)
			(end 1.3843 -1.8034)
			(stroke
				(width 0.3302)
				(type default)
			)
			(layer "F.SilkS")
		)
		(fp_line
			(start 1.27 -1.7018)
			(end 1.27 1.7018)
			(stroke
				(width 0.1524)
				(type default)
			)
			(layer "F.SilkS")
		)
		(fp_line
			(start 1.27 1.7018)
			(end -1.27 1.7018)
			(stroke
				(width 0.1524)
				(type default)
			)
			(layer "F.SilkS")
		)
		(fp_line
			(start 1.3843 -1.8034)
			(end 1.3843 -1.1176)
			(stroke
				(width 0.3302)
				(type default)
			)
			(layer "F.SilkS")
		)
		(fp_rect
			(start -1.524 1.9558)
			(end 1.524 -1.9558)
			(stroke
				(width 0)
				(type default)
			)
			(fill no)
			(layer "F.CrtYd")
		)
		(fp_poly
			(pts
				(xy -1.524 -1.9558) (xy 1.524 -1.9558) (xy 1.524 1.9558) (xy -1.524 1.9558)
			)
			(stroke
				(width 0)
				(type default)
			)
			(fill no)
			(layer "F.Fab")
		)
		(pad "1" smd rect
			(at 0.65024 -0.8255)
			(size 0.4064 1.2192)
			(layers "F.Cu" "F.Mask" "F.Paste")
			(net "SAS2X28_B_HDD3_FLT")
		)
		(pad "2" smd rect
			(at 0 -0.8255)
			(size 0.4064 1.2192)
			(layers "F.Cu" "F.Mask" "F.Paste")
			(net "SAS2X28_A_HDD3_FLT")
		)
		(pad "3" smd rect
			(at -0.65024 -0.8255)
			(size 0.4064 1.2192)
			(layers "F.Cu" "F.Mask" "F.Paste")
			(net "GND")
		)
		(pad "4" smd rect
			(at -0.65024 0.8255)
			(size 0.4064 1.2192)
			(layers "F.Cu" "F.Mask" "F.Paste")
			(net "FLT_HDD3_DRIVE")
		)
		(pad "5" smd rect
			(at 0.65024 0.8255)
			(size 0.4064 1.2192)
			(layers "F.Cu" "F.Mask" "F.Paste")
			(net "P3V3")
		)
	)
	(footprint ""
		(layer "F.Cu")
		(at 62.1284 -70.8152)
		(property "Reference" "Q64"
			(at 0 0 0)
			(layer "F.SilkS")
			(hide yes)
			(effects
				(font
					(size 1.27 1.27)
				)
			)
		)
		(property "Value" "2N7002DW-7F-GP"
			(at -2.3622 -8.2042 0)
			(unlocked yes)
			(layer "F.Fab")
			(hide yes)
			(effects
				(font
					(size 1.016 1.016)
					(thickness 0.1524)
				)
			)
		)
		(property "Device Type" "SOT-363H44"
			(at -2.3622 -10.1092 0)
			(unlocked yes)
			(layer "F.Fab")
			(hide yes)
			(effects
				(font
					(size 1.016 1.016)
					(thickness 0.1524)
				)
			)
		)
		(duplicate_pad_numbers_are_jumpers no)
		(fp_line
			(start -1.4478 -1.7018)
			(end -1.4478 1.7018)
			(stroke
				(width 0.1524)
				(type default)
			)
			(layer "F.SilkS")
		)
		(fp_line
			(start -1.4478 1.7018)
			(end 1.4478 1.7018)
			(stroke
				(width 0.1524)
				(type default)
			)
			(layer "F.SilkS")
		)
		(fp_line
			(start -1.27 1.524)
			(end -1.27 0.6604)
			(stroke
				(width 0.4826)
				(type default)
			)
			(layer "F.SilkS")
		)
		(fp_line
			(start 1.4478 -1.7018)
			(end -1.4478 -1.7018)
			(stroke
				(width 0.1524)
				(type default)
			)
			(layer "F.SilkS")
		)
		(fp_line
			(start 1.4478 1.7018)
			(end 1.4478 -1.7018)
			(stroke
				(width 0.1524)
				(type default)
			)
			(layer "F.SilkS")
		)
		(fp_poly
			(pts
				(xy -1.524 -1.778) (xy 1.524 -1.778) (xy 1.524 1.778) (xy -1.524 1.778)
			)
			(stroke
				(width 0)
				(type default)
			)
			(fill no)
			(layer "F.CrtYd")
		)
		(fp_poly
			(pts
				(xy -1.524 -1.778) (xy 1.524 -1.778) (xy 1.524 1.778) (xy -1.524 1.778)
			)
			(stroke
				(width 0)
				(type default)
			)
			(fill no)
			(layer "F.Fab")
		)
		(pad "1" smd rect
			(at -0.65024 0.9398)
			(size 0.4064 1.016)
			(layers "F.Cu" "F.Mask" "F.Paste")
			(net "P3V3_HDD9_LED")
		)
		(pad "2" smd rect
			(at 0 0.9398)
			(size 0.4064 1.016)
			(layers "F.Cu" "F.Mask" "F.Paste")
			(net "HDD9_LED_G")
		)
		(pad "3" smd rect
			(at 0.65024 0.9398)
			(size 0.4064 1.016)
			(layers "F.Cu" "F.Mask" "F.Paste")
			(net "P5VB")
		)
		(pad "4" smd rect
			(at 0.65024 -0.9398)
			(size 0.4064 1.016)
			(layers "F.Cu" "F.Mask" "F.Paste")
			(net "P5VB_HDD9_LED")
		)
		(pad "5" smd rect
			(at 0 -0.9398)
			(size 0.4064 1.016)
			(layers "F.Cu" "F.Mask" "F.Paste")
			(net "HDD9_LED_G")
		)
		(pad "6" smd rect
			(at -0.65024 -0.9398)
			(size 0.4064 1.016)
			(layers "F.Cu" "F.Mask" "F.Paste")
			(net "P3V3")
		)
	)
	(footprint ""
		(layer "F.Cu")
		(at 25.907746 -276.4917)
		(property "Reference" "R211"
			(at 0 0 0)
			(layer "F.SilkS")
			(hide yes)
			(effects
				(font
					(size 1.27 1.27)
				)
			)
		)
		(property "Value" "0R2J-2-GP"
			(at 0.064008 -3.993896 0)
			(unlocked yes)
			(layer "F.Fab")
			(hide yes)
			(effects
				(font
					(size 1.016 1.016)
					(thickness 0.1524)
				)
			)
		)
		(property "Device Type" "R402H16"
			(at 0.064008 -5.517896 0)
			(unlocked yes)
			(layer "F.Fab")
			(hide yes)
			(effects
				(font
					(size 1.016 1.016)
					(thickness 0.1524)
				)
			)
		)
		(duplicate_pad_numbers_are_jumpers no)
		(fp_line
			(start -0.508 -0.9398)
			(end -0.508 0.9398)
			(stroke
				(width 0.1524)
				(type default)
			)
			(layer "F.SilkS")
		)
		(fp_line
			(start 0.508 -0.9398)
			(end -0.508 -0.9398)
			(stroke
				(width 0.1524)
				(type default)
			)
			(layer "F.SilkS")
		)
		(fp_rect
			(start -0.508 0.9398)
			(end 0.508 -0.9398)
			(stroke
				(width 0)
				(type default)
			)
			(fill no)
			(layer "F.CrtYd")
		)
		(fp_rect
			(start -0.508 0.9398)
			(end 0.508 -0.9398)
			(stroke
				(width 0)
				(type default)
			)
			(fill no)
			(layer "F.Fab")
		)
		(pad "1" smd custom
			(at 0 -0.4445)
			(size 0.1397 0.1397)
			(layers "F.Cu" "F.Mask" "F.Paste")
			(net "DRIVE_PWR7")
			(options
				(clearance outline)
				(anchor circle)
			)
			(primitives
				(gr_poly
					(pts
						(arc
							(start -0.1778 -0.2794)
							(mid -0.249642 -0.249642)
							(end -0.2794 -0.1778)
						)
						(arc
							(start -0.2794 0.1778)
							(mid -0.249642 0.249642)
							(end -0.1778 0.2794)
						)
						(arc
							(start 0.1778 0.2794)
							(mid 0.249642 0.249642)
							(end 0.2794 0.1778)
						)
						(arc
							(start 0.2794 -0.1778)
							(mid 0.249642 -0.249642)
							(end 0.1778 -0.2794)
						)
					)
					(width 0)
					(fill yes)
				)
			)
		)
		(pad "2" smd custom
			(at 0 0.4445)
			(size 0.1397 0.1397)
			(layers "F.Cu" "F.Mask" "F.Paste")
			(net "SW_PWR_HDD7")
			(options
				(clearance outline)
				(anchor circle)
			)
			(primitives
				(gr_poly
					(pts
						(arc
							(start -0.1778 -0.2794)
							(mid -0.249642 -0.249642)
							(end -0.2794 -0.1778)
						)
						(arc
							(start -0.2794 0.1778)
							(mid -0.249642 0.249642)
							(end -0.1778 0.2794)
						)
						(arc
							(start 0.1778 0.2794)
							(mid 0.249642 0.249642)
							(end 0.2794 0.1778)
						)
						(arc
							(start 0.2794 -0.1778)
							(mid 0.249642 -0.249642)
							(end 0.1778 -0.2794)
						)
					)
					(width 0)
					(fill yes)
				)
			)
		)
	)
)
